(kicad_pcb
	(version 20241229)
	(generator "pcbnew")
	(generator_version "9.0")
	(general
		(thickness 1.62)
		(legacy_teardrops no)
	)
	(paper "A3")
	(title_block
		(title "COM Express 7 Baseboard")
		(date "2025-02-04")
		(rev "1.1.2")
		(company "Antmicro Ltd")
		(comment 1 "www.antmicro.com")
		(comment 9 "footprint 486 of 802 (U45), pads 119-144 of 144")
	)
	(layers
		(0 "F.Cu" signal)
		(4 "In1.Cu" signal)
		(6 "In2.Cu" signal)
		(8 "In3.Cu" signal)
		(10 "In4.Cu" signal)
		(12 "In5.Cu" signal)
		(14 "In6.Cu" signal)
		(2 "B.Cu" signal)
		(9 "F.Adhes" user "F.Adhesive")
		(11 "B.Adhes" user "B.Adhesive")
		(13 "F.Paste" user)
		(15 "B.Paste" user)
		(5 "F.SilkS" user "F.Silkscreen")
		(7 "B.SilkS" user "B.Silkscreen")
		(1 "F.Mask" user)
		(3 "B.Mask" user)
		(17 "Dwgs.User" user "User.Drawings")
		(19 "Cmts.User" user "User.Comments")
		(21 "Eco1.User" user "User.Eco1")
		(23 "Eco2.User" user "User.Eco2")
		(25 "Edge.Cuts" user)
		(27 "Margin" user)
		(31 "F.CrtYd" user "F.Courtyard")
		(29 "B.CrtYd" user "B.Courtyard")
		(35 "F.Fab" user)
		(33 "B.Fab" user)
	)
	(footprint "antmicro-footprints:BGA-144_12x12_13.05x13.05mm_P1.0mm"
		(layer "F.Cu")
		(at 132.79 137.36 -90)
		(property "Reference" "U45"
			(at 7.9 4.85 180)
			(layer "F.SilkS")
			(effects
				(font
					(size 0.7 0.7)
					(thickness 0.15)
				)
				(justify right bottom)
			)
		)
		(property "Value" "TLK10232CTR"
			(at 0 7.525 90)
			(layer "F.Fab")
			(effects
				(font
					(size 0.7 0.7)
					(thickness 0.15)
				)
				(justify right bottom)
			)
		)
		(property "Datasheet" "https://www.ti.com/lit/ds/symlink/tlk10232.pdf?ts=1712150848075&ref_url=https%253A%252F%252Fwww.mouser.pl%252F"
			(at 0 0 270)
			(layer "F.Fab")
			(hide yes)
			(effects
				(font
					(size 1.27 1.27)
					(thickness 0.15)
				)
			)
		)
		(property "Author" "Antmicro"
			(at -4.57 270.15 0)
			(layer "F.Fab")
			(hide yes)
			(effects
				(font
					(size 1 1)
					(thickness 0.15)
				)
			)
		)
		(property "License" "Apache-2.0"
			(at -4.57 270.15 0)
			(layer "F.Fab")
			(hide yes)
			(effects
				(font
					(size 1 1)
					(thickness 0.15)
				)
			)
		)
		(property "MPN" "TLK10232CTR"
			(at -4.57 270.15 0)
			(layer "F.Fab")
			(hide yes)
			(effects
				(font
					(size 1 1)
					(thickness 0.15)
				)
			)
		)
		(property "Manufacturer" "Texas Instruments"
			(at -4.57 270.15 0)
			(layer "F.Fab")
			(hide yes)
			(effects
				(font
					(size 1 1)
					(thickness 0.15)
				)
			)
		)
		(sheetname "KR to SFI #2")
		(sheetfile "kr_sfi.kicad_sch")
		(attr smd)
		(pad "K11" smd circle
			(at 4.5 3.5 270)
			(size 0.5 0.5)
			(layers "F.Cu" "F.Mask" "F.Paste")
			(net 1 "GND")
			(pinfunction "GND")
			(pintype "passive")
			(solder_mask_margin 0.05)
			(teardrops
				(best_length_ratio 0.4)
				(max_length 1)
				(best_width_ratio 0.9)
				(max_width 2)
				(curved_edges yes)
				(filter_ratio 0.9)
				(enabled yes)
				(allow_two_segments yes)
				(prefer_zone_connections yes)
			)
		)
		(pad "K12" smd circle
			(at 5.5 3.5 270)
			(size 0.5 0.5)
			(layers "F.Cu" "F.Mask" "F.Paste")
			(net 947 "/2xSFP+/KR to SFI #2/SFI_R.TX+")
			(pinfunction "HSTXB+")
			(pintype "output")
			(solder_mask_margin 0.05)
			(teardrops
				(best_length_ratio 0.4)
				(max_length 1)
				(best_width_ratio 0.9)
				(max_width 2)
				(curved_edges yes)
				(filter_ratio 0.9)
				(enabled yes)
				(allow_two_segments yes)
				(prefer_zone_connections yes)
			)
		)
		(pad "L1" smd circle
			(at -5.5 4.5 270)
			(size 0.5 0.5)
			(layers "F.Cu" "F.Mask" "F.Paste")
			(net 855 "unconnected-(U45B-INB2+-PadL1)")
			(pinfunction "INB2+")
			(pintype "input+no_connect")
			(solder_mask_margin 0.05)
			(teardrops
				(best_length_ratio 0.4)
				(max_length 1)
				(best_width_ratio 0.9)
				(max_width 2)
				(curved_edges yes)
				(filter_ratio 0.9)
				(enabled yes)
				(allow_two_segments yes)
				(prefer_zone_connections yes)
			)
		)
		(pad "L2" smd circle
			(at -4.5 4.5 270)
			(size 0.5 0.5)
			(layers "F.Cu" "F.Mask" "F.Paste")
			(net 856 "unconnected-(U45B-INB1--PadL2)")
			(pinfunction "INB1-")
			(pintype "input+no_connect")
			(solder_mask_margin 0.05)
			(teardrops
				(best_length_ratio 0.4)
				(max_length 1)
				(best_width_ratio 0.9)
				(max_width 2)
				(curved_edges yes)
				(filter_ratio 0.9)
				(enabled yes)
				(allow_two_segments yes)
				(prefer_zone_connections yes)
			)
		)
		(pad "L3" smd circle
			(at -3.5 4.5 270)
			(size 0.5 0.5)
			(layers "F.Cu" "F.Mask" "F.Paste")
			(net 1 "GND")
			(pinfunction "GND")
			(pintype "passive")
			(solder_mask_margin 0.05)
			(teardrops
				(best_length_ratio 0.4)
				(max_length 1)
				(best_width_ratio 0.9)
				(max_width 2)
				(curved_edges yes)
				(filter_ratio 0.9)
				(enabled yes)
				(allow_two_segments yes)
				(prefer_zone_connections yes)
			)
		)
		(pad "L4" smd circle
			(at -2.5 4.5 270)
			(size 0.5 0.5)
			(layers "F.Cu" "F.Mask" "F.Paste")
			(net 1 "GND")
			(pinfunction "GND")
			(pintype "passive")
			(solder_mask_margin 0.05)
			(teardrops
				(best_length_ratio 0.4)
				(max_length 1)
				(best_width_ratio 0.9)
				(max_width 2)
				(curved_edges yes)
				(filter_ratio 0.9)
				(enabled yes)
				(allow_two_segments yes)
				(prefer_zone_connections yes)
			)
		)
		(pad "L5" smd circle
			(at -1.5 4.5 270)
			(size 0.5 0.5)
			(layers "F.Cu" "F.Mask" "F.Paste")
			(net 857 "unconnected-(U45B-OUTB2--PadL5)")
			(pinfunction "OUTB2-")
			(pintype "output+no_connect")
			(solder_mask_margin 0.05)
			(teardrops
				(best_length_ratio 0.4)
				(max_length 1)
				(best_width_ratio 0.9)
				(max_width 2)
				(curved_edges yes)
				(filter_ratio 0.9)
				(enabled yes)
				(allow_two_segments yes)
				(prefer_zone_connections yes)
			)
		)
		(pad "L6" smd circle
			(at -0.5 4.5 270)
			(size 0.5 0.5)
			(layers "F.Cu" "F.Mask" "F.Paste")
			(net 858 "unconnected-(U45B-OUTB2+-PadL6)")
			(pinfunction "OUTB2+")
			(pintype "output+no_connect")
			(solder_mask_margin 0.05)
			(teardrops
				(best_length_ratio 0.4)
				(max_length 1)
				(best_width_ratio 0.9)
				(max_width 2)
				(curved_edges yes)
				(filter_ratio 0.9)
				(enabled yes)
				(allow_two_segments yes)
				(prefer_zone_connections yes)
			)
		)
		(pad "L7" smd circle
			(at 0.5 4.5 270)
			(size 0.5 0.5)
			(layers "F.Cu" "F.Mask" "F.Paste")
			(net 1 "GND")
			(pinfunction "GND")
			(pintype "passive")
			(solder_mask_margin 0.05)
			(teardrops
				(best_length_ratio 0.4)
				(max_length 1)
				(best_width_ratio 0.9)
				(max_width 2)
				(curved_edges yes)
				(filter_ratio 0.9)
				(enabled yes)
				(allow_two_segments yes)
				(prefer_zone_connections yes)
			)
		)
		(pad "L8" smd circle
			(at 1.5 4.5 270)
			(size 0.5 0.5)
			(layers "F.Cu" "F.Mask" "F.Paste")
			(net 758 "Net-(U45B-LS_OK_{IN_B})")
			(pinfunction "LS_OK_{IN_B}")
			(pintype "input")
			(solder_mask_margin 0.05)
			(teardrops
				(best_length_ratio 0.4)
				(max_length 1)
				(best_width_ratio 0.9)
				(max_width 2)
				(curved_edges yes)
				(filter_ratio 0.9)
				(enabled yes)
				(allow_two_segments yes)
				(prefer_zone_connections yes)
			)
		)
		(pad "L9" smd circle
			(at 2.5 4.5 270)
			(size 0.5 0.5)
			(layers "F.Cu" "F.Mask" "F.Paste")
			(net 679 "Net-(U45C-PRTAD2)")
			(pinfunction "PRTAD2")
			(pintype "input")
			(solder_mask_margin 0.05)
			(teardrops
				(best_length_ratio 0.4)
				(max_length 1)
				(best_width_ratio 0.9)
				(max_width 2)
				(curved_edges yes)
				(filter_ratio 0.9)
				(enabled yes)
				(allow_two_segments yes)
				(prefer_zone_connections yes)
			)
		)
		(pad "L10" smd circle
			(at 3.5 4.5 270)
			(size 0.5 0.5)
			(layers "F.Cu" "F.Mask" "F.Paste")
			(net 674 "Net-(U45C-TESTEN)")
			(pinfunction "TESTEN")
			(pintype "input")
			(solder_mask_margin 0.05)
			(teardrops
				(best_length_ratio 0.4)
				(max_length 1)
				(best_width_ratio 0.9)
				(max_width 2)
				(curved_edges yes)
				(filter_ratio 0.9)
				(enabled yes)
				(allow_two_segments yes)
				(prefer_zone_connections yes)
			)
		)
		(pad "L11" smd circle
			(at 4.5 4.5 270)
			(size 0.5 0.5)
			(layers "F.Cu" "F.Mask" "F.Paste")
			(net 1 "GND")
			(pinfunction "GND")
			(pintype "passive")
			(solder_mask_margin 0.05)
			(teardrops
				(best_length_ratio 0.4)
				(max_length 1)
				(best_width_ratio 0.9)
				(max_width 2)
				(curved_edges yes)
				(filter_ratio 0.9)
				(enabled yes)
				(allow_two_segments yes)
				(prefer_zone_connections yes)
			)
		)
		(pad "L12" smd circle
			(at 5.5 4.5 270)
			(size 0.5 0.5)
			(layers "F.Cu" "F.Mask" "F.Paste")
			(net 952 "/2xSFP+/KR to SFI #2/SFI_R.TX-")
			(pinfunction "HSTXB-")
			(pintype "output")
			(solder_mask_margin 0.05)
			(teardrops
				(best_length_ratio 0.4)
				(max_length 1)
				(best_width_ratio 0.9)
				(max_width 2)
				(curved_edges yes)
				(filter_ratio 0.9)
				(enabled yes)
				(allow_two_segments yes)
				(prefer_zone_connections yes)
			)
		)
		(pad "M1" smd circle
			(at -5.5 5.5 270)
			(size 0.5 0.5)
			(layers "F.Cu" "F.Mask" "F.Paste")
			(net 859 "unconnected-(U45B-INB2--PadM1)")
			(pinfunction "INB2-")
			(pintype "input+no_connect")
			(solder_mask_margin 0.05)
			(teardrops
				(best_length_ratio 0.4)
				(max_length 1)
				(best_width_ratio 0.9)
				(max_width 2)
				(curved_edges yes)
				(filter_ratio 0.9)
				(enabled yes)
				(allow_two_segments yes)
				(prefer_zone_connections yes)
			)
		)
		(pad "M2" smd circle
			(at -4.5 5.5 270)
			(size 0.5 0.5)
			(layers "F.Cu" "F.Mask" "F.Paste")
			(net 1 "GND")
			(pinfunction "GND")
			(pintype "passive")
			(solder_mask_margin 0.05)
			(teardrops
				(best_length_ratio 0.4)
				(max_length 1)
				(best_width_ratio 0.9)
				(max_width 2)
				(curved_edges yes)
				(filter_ratio 0.9)
				(enabled yes)
				(allow_two_segments yes)
				(prefer_zone_connections yes)
			)
		)
		(pad "M3" smd circle
			(at -3.5 5.5 270)
			(size 0.5 0.5)
			(layers "F.Cu" "F.Mask" "F.Paste")
			(net 860 "unconnected-(U45B-INB3+-PadM3)")
			(pinfunction "INB3+")
			(pintype "input+no_connect")
			(solder_mask_margin 0.05)
			(teardrops
				(best_length_ratio 0.4)
				(max_length 1)
				(best_width_ratio 0.9)
				(max_width 2)
				(curved_edges yes)
				(filter_ratio 0.9)
				(enabled yes)
				(allow_two_segments yes)
				(prefer_zone_connections yes)
			)
		)
		(pad "M4" smd circle
			(at -2.5 5.5 270)
			(size 0.5 0.5)
			(layers "F.Cu" "F.Mask" "F.Paste")
			(net 861 "unconnected-(U45B-INB3--PadM4)")
			(pinfunction "INB3-")
			(pintype "input+no_connect")
			(solder_mask_margin 0.05)
			(teardrops
				(best_length_ratio 0.4)
				(max_length 1)
				(best_width_ratio 0.9)
				(max_width 2)
				(curved_edges yes)
				(filter_ratio 0.9)
				(enabled yes)
				(allow_two_segments yes)
				(prefer_zone_connections yes)
			)
		)
		(pad "M5" smd circle
			(at -1.5 5.5 270)
			(size 0.5 0.5)
			(layers "F.Cu" "F.Mask" "F.Paste")
			(net 1 "GND")
			(pinfunction "GND")
			(pintype "passive")
			(solder_mask_margin 0.05)
			(teardrops
				(best_length_ratio 0.4)
				(max_length 1)
				(best_width_ratio 0.9)
				(max_width 2)
				(curved_edges yes)
				(filter_ratio 0.9)
				(enabled yes)
				(allow_two_segments yes)
				(prefer_zone_connections yes)
			)
		)
		(pad "M6" smd circle
			(at -0.5 5.5 270)
			(size 0.5 0.5)
			(layers "F.Cu" "F.Mask" "F.Paste")
			(net 862 "unconnected-(U45B-OUTB3--PadM6)")
			(pinfunction "OUTB3-")
			(pintype "output+no_connect")
			(solder_mask_margin 0.05)
			(teardrops
				(best_length_ratio 0.4)
				(max_length 1)
				(best_width_ratio 0.9)
				(max_width 2)
				(curved_edges yes)
				(filter_ratio 0.9)
				(enabled yes)
				(allow_two_segments yes)
				(prefer_zone_connections yes)
			)
		)
		(pad "M7" smd circle
			(at 0.5 5.5 270)
			(size 0.5 0.5)
			(layers "F.Cu" "F.Mask" "F.Paste")
			(net 863 "unconnected-(U45B-OUTB3+-PadM7)")
			(pinfunction "OUTB3+")
			(pintype "output+no_connect")
			(solder_mask_margin 0.05)
			(teardrops
				(best_length_ratio 0.4)
				(max_length 1)
				(best_width_ratio 0.9)
				(max_width 2)
				(curved_edges yes)
				(filter_ratio 0.9)
				(enabled yes)
				(allow_two_segments yes)
				(prefer_zone_connections yes)
			)
		)
		(pad "M8" smd circle
			(at 1.5 5.5 270)
			(size 0.5 0.5)
			(layers "F.Cu" "F.Mask" "F.Paste")
			(net 682 "Net-(U45C-PRTAD4)")
			(pinfunction "PRTAD4")
			(pintype "input")
			(solder_mask_margin 0.05)
			(teardrops
				(best_length_ratio 0.4)
				(max_length 1)
				(best_width_ratio 0.9)
				(max_width 2)
				(curved_edges yes)
				(filter_ratio 0.9)
				(enabled yes)
				(allow_two_segments yes)
				(prefer_zone_connections yes)
			)
		)
		(pad "M9" smd circle
			(at 2.5 5.5 270)
			(size 0.5 0.5)
			(layers "F.Cu" "F.Mask" "F.Paste")
			(net 684 "Net-(U45C-ST)")
			(pinfunction "ST")
			(pintype "input")
			(solder_mask_margin 0.05)
			(teardrops
				(best_length_ratio 0.4)
				(max_length 1)
				(best_width_ratio 0.9)
				(max_width 2)
				(curved_edges yes)
				(filter_ratio 0.9)
				(enabled yes)
				(allow_two_segments yes)
				(prefer_zone_connections yes)
			)
		)
		(pad "M10" smd circle
			(at 3.5 5.5 270)
			(size 0.5 0.5)
			(layers "F.Cu" "F.Mask" "F.Paste")
			(net 116 "/2xSFP+/KR to SFI #2/REFCLK+")
			(pinfunction "REFCLK0+")
			(pintype "input")
			(solder_mask_margin 0.05)
			(teardrops
				(best_length_ratio 0.4)
				(max_length 1)
				(best_width_ratio 0.9)
				(max_width 2)
				(curved_edges yes)
				(filter_ratio 0.9)
				(enabled yes)
				(allow_two_segments yes)
				(prefer_zone_connections yes)
			)
		)
		(pad "M11" smd circle
			(at 4.5 5.5 270)
			(size 0.5 0.5)
			(layers "F.Cu" "F.Mask" "F.Paste")
			(net 118 "/2xSFP+/KR to SFI #2/REFCLK-")
			(pinfunction "REFCLK0-")
			(pintype "input")
			(solder_mask_margin 0.05)
			(teardrops
				(best_length_ratio 0.4)
				(max_length 1)
				(best_width_ratio 0.9)
				(max_width 2)
				(curved_edges yes)
				(filter_ratio 0.9)
				(enabled yes)
				(allow_two_segments yes)
				(prefer_zone_connections yes)
			)
		)
		(pad "M12" smd circle
			(at 5.5 5.5 270)
			(size 0.5 0.5)
			(layers "F.Cu" "F.Mask" "F.Paste")
			(net 1 "GND")
			(pinfunction "GND")
			(pintype "passive")
			(solder_mask_margin 0.05)
			(teardrops
				(best_length_ratio 0.4)
				(max_length 1)
				(best_width_ratio 0.9)
				(max_width 2)
				(curved_edges yes)
				(filter_ratio 0.9)
				(enabled yes)
				(allow_two_segments yes)
				(prefer_zone_connections yes)
			)
		)
	)
)
